(kicad_pcb
	(version 20260206)
	(generator "pcbnew")
	(generator_version "10.0")
	(general
		(thickness 1.6)
		(legacy_teardrops no)
	)
	(paper "A4")
	(title_block
		(title "baseboard — 13948-1b.1110WZS1818.brd")
		(comment 1 "Honey Badger (Wiwynn) / footprint 84 of 2523 (GF1), pads 109-164 of 164")
	)
	(layers
		(0 "F.Cu" signal "TOP")
		(4 "In1.Cu" signal "L2GND")
		(6 "In2.Cu" signal "L3")
		(8 "In3.Cu" signal "L4VCC")
		(10 "In4.Cu" signal "L5VCC")
		(12 "In5.Cu" signal "L6")
		(14 "In6.Cu" signal "L7GND")
		(2 "B.Cu" signal "BOTTOM")
		(9 "F.Adhes" user "F.Adhesive")
		(11 "B.Adhes" user "B.Adhesive")
		(13 "F.Paste" user "Package Geometry/Pastemask Top")
		(15 "B.Paste" user "Package Geometry/Pastemask Bottom")
		(5 "F.SilkS" user "Ref Des/Silkscreen Top")
		(7 "B.SilkS" user "Ref Des/Silkscreen Bottom")
		(1 "F.Mask" user "Board Geometry/Soldermask Top")
		(3 "B.Mask" user "Board Geometry/Soldermask Bottom")
		(17 "Dwgs.User" user "User.Drawings")
		(19 "Cmts.User" user "User.Comments")
		(21 "Eco1.User" user "User.Eco1")
		(23 "Eco2.User" user "User.Eco2")
		(25 "Edge.Cuts" user "Board Geometry/Outline")
		(27 "Margin" user)
		(31 "F.CrtYd" user "Package Geometry/Place Bound Top")
		(29 "B.CrtYd" user "Package Geometry/Place Bound Bottom")
		(35 "F.Fab" user "Ref Des/Assembly Top")
		(33 "B.Fab" user "Ref Des/Assembly Bottom")
	)
	(footprint ""
		(layer "F.Cu")
		(at 139.500102 -258.59994 180)
		(property "Reference" "GF1"
			(at 0 0 180)
			(layer "F.SilkS")
			(hide yes)
			(effects
				(font
					(size 1.27 1.27)
				)
			)
		)
		(property "Value" "GF-X16-U"
			(at 12.048744 -9.339834 180)
			(unlocked yes)
			(layer "F.Fab")
			(hide yes)
			(effects
				(font
					(size 1.016 1.016)
					(thickness 0.1524)
				)
			)
		)
		(property "Device Type" "GF-X16-U"
			(at 12.048744 -10.863834 180)
			(unlocked yes)
			(layer "F.Fab")
			(hide yes)
			(effects
				(font
					(size 1.016 1.016)
					(thickness 0.1524)
				)
			)
		)
		(duplicate_pad_numbers_are_jumpers no)
		(pad "B27" smd rect
			(at 16.49984 -2.3495 180)
			(size 0.7112 4.191)
			(drill
				(offset 0 0.254)
			)
			(layers "F.Cu" "F.Mask" "F.Paste")
			(net "GND")
		)
		(pad "B28" smd rect
			(at 17.5006 -2.3495 180)
			(size 0.7112 4.191)
			(drill
				(offset 0 0.254)
			)
			(layers "F.Cu" "F.Mask" "F.Paste")
			(net "SAS_EXP_GF_TX_DP6")
		)
		(pad "B29" smd rect
			(at 18.50009 -2.3495 180)
			(size 0.7112 4.191)
			(drill
				(offset 0 0.254)
			)
			(layers "F.Cu" "F.Mask" "F.Paste")
			(net "SAS_EXP_GF_TX_DN6")
		)
		(pad "B30" smd rect
			(at 19.49958 -2.3495 180)
			(size 0.7112 4.191)
			(drill
				(offset 0 0.254)
			)
			(layers "F.Cu" "F.Mask" "F.Paste")
			(net "GND")
		)
		(pad "B31" smd rect
			(at 20.50034 -2.3495 180)
			(size 0.7112 4.191)
			(drill
				(offset 0 0.254)
			)
			(layers "F.Cu" "F.Mask" "F.Paste")
			(net "GND")
		)
		(pad "B32" smd rect
			(at 21.49983 -2.3495 180)
			(size 0.7112 4.191)
			(drill
				(offset 0 0.254)
			)
			(layers "F.Cu" "F.Mask" "F.Paste")
			(net "SAS_HDD_CONN_TX7_P")
		)
		(pad "B33" smd rect
			(at 22.50059 -2.3495 180)
			(size 0.7112 4.191)
			(drill
				(offset 0 0.254)
			)
			(layers "F.Cu" "F.Mask" "F.Paste")
			(net "SAS_HDD_CONN_TX7_N")
		)
		(pad "B34" smd rect
			(at 23.50008 -2.3495 180)
			(size 0.7112 4.191)
			(drill
				(offset 0 0.254)
			)
			(layers "F.Cu" "F.Mask" "F.Paste")
			(net "GND")
		)
		(pad "B35" smd rect
			(at 24.49957 -2.3495 180)
			(size 0.7112 4.191)
			(drill
				(offset 0 0.254)
			)
			(layers "F.Cu" "F.Mask" "F.Paste")
			(net "GND")
		)
		(pad "B36" smd rect
			(at 25.50033 -2.3495 180)
			(size 0.7112 4.191)
			(drill
				(offset 0 0.254)
			)
			(layers "F.Cu" "F.Mask" "F.Paste")
			(net "SAS_HDD_CONN_TX8_P")
		)
		(pad "B37" smd rect
			(at 26.49982 -2.3495 180)
			(size 0.7112 4.191)
			(drill
				(offset 0 0.254)
			)
			(layers "F.Cu" "F.Mask" "F.Paste")
			(net "SAS_HDD_CONN_TX8_N")
		)
		(pad "B38" smd rect
			(at 27.50058 -2.3495 180)
			(size 0.7112 4.191)
			(drill
				(offset 0 0.254)
			)
			(layers "F.Cu" "F.Mask" "F.Paste")
			(net "GND")
		)
		(pad "B39" smd rect
			(at 28.50007 -2.3495 180)
			(size 0.7112 4.191)
			(drill
				(offset 0 0.254)
			)
			(layers "F.Cu" "F.Mask" "F.Paste")
			(net "GND")
		)
		(pad "B40" smd rect
			(at 29.49956 -2.3495 180)
			(size 0.7112 4.191)
			(drill
				(offset 0 0.254)
			)
			(layers "F.Cu" "F.Mask" "F.Paste")
			(net "SAS_EXP_GF_TX_DP9")
		)
		(pad "B41" smd rect
			(at 30.50032 -2.3495 180)
			(size 0.7112 4.191)
			(drill
				(offset 0 0.254)
			)
			(layers "F.Cu" "F.Mask" "F.Paste")
			(net "SAS_EXP_GF_TX_DN9")
		)
		(pad "B42" smd rect
			(at 31.49981 -2.3495 180)
			(size 0.7112 4.191)
			(drill
				(offset 0 0.254)
			)
			(layers "F.Cu" "F.Mask" "F.Paste")
			(net "GND")
		)
		(pad "B43" smd rect
			(at 32.50057 -2.3495 180)
			(size 0.7112 4.191)
			(drill
				(offset 0 0.254)
			)
			(layers "F.Cu" "F.Mask" "F.Paste")
			(net "SAS_FAULT_LED9")
		)
		(pad "B44" smd rect
			(at 33.50006 -2.3495 180)
			(size 0.7112 4.191)
			(drill
				(offset 0 0.254)
			)
			(layers "F.Cu" "F.Mask" "F.Paste")
			(net "SAS_FAULT_LED10")
		)
		(pad "B45" smd rect
			(at 34.49955 -2.3495 180)
			(size 0.7112 4.191)
			(drill
				(offset 0 0.254)
			)
			(layers "F.Cu" "F.Mask" "F.Paste")
			(net "SAS_FAULT_LED11")
		)
		(pad "B46" smd rect
			(at 35.50031 -2.3495 180)
			(size 0.7112 4.191)
			(drill
				(offset 0 0.254)
			)
			(layers "F.Cu" "F.Mask" "F.Paste")
			(net "SAS_FAULT_LED12")
		)
		(pad "B47" smd rect
			(at 36.4998 -2.3495 180)
			(size 0.7112 4.191)
			(drill
				(offset 0 0.254)
			)
			(layers "F.Cu" "F.Mask" "F.Paste")
			(net "SAS_FAULT_LED13")
		)
		(pad "B48" smd rect
			(at 37.50056 -2.3495 180)
			(size 0.7112 4.191)
			(drill
				(offset 0 0.254)
			)
			(layers "F.Cu" "F.Mask" "F.Paste")
			(net "GND")
		)
		(pad "B49" smd rect
			(at 38.50005 -2.3495 180)
			(size 0.7112 4.191)
			(drill
				(offset 0 0.254)
			)
			(layers "F.Cu" "F.Mask" "F.Paste")
			(net "SAS_EXP_GF_TX_DP10")
		)
		(pad "B50" smd rect
			(at 39.49954 -2.3495 180)
			(size 0.7112 4.191)
			(drill
				(offset 0 0.254)
			)
			(layers "F.Cu" "F.Mask" "F.Paste")
			(net "SAS_EXP_GF_TX_DN10")
		)
		(pad "B51" smd rect
			(at 40.5003 -2.3495 180)
			(size 0.7112 4.191)
			(drill
				(offset 0 0.254)
			)
			(layers "F.Cu" "F.Mask" "F.Paste")
			(net "GND")
		)
		(pad "B52" smd rect
			(at 41.49979 -2.3495 180)
			(size 0.7112 4.191)
			(drill
				(offset 0 0.254)
			)
			(layers "F.Cu" "F.Mask" "F.Paste")
			(net "SAS_FAULT_LED14")
		)
		(pad "B53" smd rect
			(at 42.50055 -2.3495 180)
			(size 0.7112 4.191)
			(drill
				(offset 0 0.254)
			)
			(layers "F.Cu" "F.Mask" "F.Paste")
			(net "SAS_FAULT_LED15")
		)
		(pad "B54" smd rect
			(at 43.50004 -2.3495 180)
			(size 0.7112 4.191)
			(drill
				(offset 0 0.254)
			)
			(layers "F.Cu" "F.Mask" "F.Paste")
			(net "HB_OUT")
		)
		(pad "B55" smd rect
			(at 44.49953 -2.3495 180)
			(size 0.7112 4.191)
			(drill
				(offset 0 0.254)
			)
			(layers "F.Cu" "F.Mask" "F.Paste")
			(net "HB_INPUT")
		)
		(pad "B56" smd rect
			(at 45.50029 -2.3495 180)
			(size 0.7112 4.191)
			(drill
				(offset 0 0.254)
			)
			(layers "F.Cu" "F.Mask" "F.Paste")
			(net "SAS_I2C_B_BUF_SCL_R")
		)
		(pad "B57" smd rect
			(at 46.49978 -2.3495 180)
			(size 0.7112 4.191)
			(drill
				(offset 0 0.254)
			)
			(layers "F.Cu" "F.Mask" "F.Paste")
			(net "SAS_I2C_B_BUF_SDA_R")
		)
		(pad "B58" smd rect
			(at 47.50054 -2.3495 180)
			(size 0.7112 4.191)
			(drill
				(offset 0 0.254)
			)
			(layers "F.Cu" "F.Mask" "F.Paste")
			(net "ID_I2C_ADD")
		)
		(pad "B59" smd rect
			(at 48.50003 -2.3495 180)
			(size 0.7112 4.191)
			(drill
				(offset 0 0.254)
			)
			(layers "F.Cu" "F.Mask" "F.Paste")
			(net "FAN_PWM_PCIE")
		)
		(pad "B60" smd rect
			(at 49.49952 -2.3495 180)
			(size 0.7112 4.191)
			(drill
				(offset 0 0.254)
			)
			(layers "F.Cu" "F.Mask" "F.Paste")
			(net "PEER_1A_2A_HB")
		)
		(pad "B61" smd rect
			(at 50.50028 -2.3495 180)
			(size 0.7112 4.191)
			(drill
				(offset 0 0.254)
			)
			(layers "F.Cu" "F.Mask" "F.Paste")
			(net "GND")
		)
		(pad "B62" smd rect
			(at 51.49977 -2.3495 180)
			(size 0.7112 4.191)
			(drill
				(offset 0 0.254)
			)
			(layers "F.Cu" "F.Mask" "F.Paste")
			(net "SAS_EXP_GF_TX_DP11")
		)
		(pad "B63" smd rect
			(at 52.50053 -2.3495 180)
			(size 0.7112 4.191)
			(drill
				(offset 0 0.254)
			)
			(layers "F.Cu" "F.Mask" "F.Paste")
			(net "SAS_EXP_GF_TX_DN11")
		)
		(pad "B64" smd rect
			(at 53.50002 -2.3495 180)
			(size 0.7112 4.191)
			(drill
				(offset 0 0.254)
			)
			(layers "F.Cu" "F.Mask" "F.Paste")
			(net "GND")
		)
		(pad "B65" smd rect
			(at 54.50078 -2.3495 180)
			(size 0.7112 4.191)
			(drill
				(offset 0 0.254)
			)
			(layers "F.Cu" "F.Mask" "F.Paste")
			(net "GND")
		)
		(pad "B66" smd rect
			(at 55.50027 -2.3495 180)
			(size 0.7112 4.191)
			(drill
				(offset 0 0.254)
			)
			(layers "F.Cu" "F.Mask" "F.Paste")
			(net "SAS_EXP_GF_TX_DP12")
		)
		(pad "B67" smd rect
			(at 56.49976 -2.3495 180)
			(size 0.7112 4.191)
			(drill
				(offset 0 0.254)
			)
			(layers "F.Cu" "F.Mask" "F.Paste")
			(net "SAS_EXP_GF_TX_DN12")
		)
		(pad "B68" smd rect
			(at 57.50052 -2.3495 180)
			(size 0.7112 4.191)
			(drill
				(offset 0 0.254)
			)
			(layers "F.Cu" "F.Mask" "F.Paste")
			(net "GND")
		)
		(pad "B69" smd rect
			(at 58.50001 -2.3495 180)
			(size 0.7112 4.191)
			(drill
				(offset 0 0.254)
			)
			(layers "F.Cu" "F.Mask" "F.Paste")
			(net "GND")
		)
		(pad "B70" smd rect
			(at 59.50077 -2.3495 180)
			(size 0.7112 4.191)
			(drill
				(offset 0 0.254)
			)
			(layers "F.Cu" "F.Mask" "F.Paste")
			(net "SAS_EXP_GF_TX_DP13")
		)
		(pad "B71" smd rect
			(at 60.50026 -2.3495 180)
			(size 0.7112 4.191)
			(drill
				(offset 0 0.254)
			)
			(layers "F.Cu" "F.Mask" "F.Paste")
			(net "SAS_EXP_GF_TX_DN13")
		)
		(pad "B72" smd rect
			(at 61.49975 -2.3495 180)
			(size 0.7112 4.191)
			(drill
				(offset 0 0.254)
			)
			(layers "F.Cu" "F.Mask" "F.Paste")
			(net "GND")
		)
		(pad "B73" smd rect
			(at 62.50051 -2.3495 180)
			(size 0.7112 4.191)
			(drill
				(offset 0 0.254)
			)
			(layers "F.Cu" "F.Mask" "F.Paste")
			(net "GND")
		)
		(pad "B74" smd rect
			(at 63.5 -2.3495 180)
			(size 0.7112 4.191)
			(drill
				(offset 0 0.254)
			)
			(layers "F.Cu" "F.Mask" "F.Paste")
			(net "SAS_EXP_GF_TX_DP14")
		)
		(pad "B75" smd rect
			(at 64.50076 -2.3495 180)
			(size 0.7112 4.191)
			(drill
				(offset 0 0.254)
			)
			(layers "F.Cu" "F.Mask" "F.Paste")
			(net "SAS_EXP_GF_TX_DN14")
		)
		(pad "B76" smd rect
			(at 65.50025 -2.3495 180)
			(size 0.7112 4.191)
			(drill
				(offset 0 0.254)
			)
			(layers "F.Cu" "F.Mask" "F.Paste")
			(net "GND")
		)
		(pad "B77" smd rect
			(at 66.49974 -2.3495 180)
			(size 0.7112 4.191)
			(drill
				(offset 0 0.254)
			)
			(layers "F.Cu" "F.Mask" "F.Paste")
			(net "GND")
		)
		(pad "B78" smd rect
			(at 67.5005 -2.3495 180)
			(size 0.7112 4.191)
			(drill
				(offset 0 0.254)
			)
			(layers "F.Cu" "F.Mask" "F.Paste")
			(net "SAS_EXP_GF_TX_DP15")
		)
		(pad "B79" smd rect
			(at 68.49999 -2.3495 180)
			(size 0.7112 4.191)
			(drill
				(offset 0 0.254)
			)
			(layers "F.Cu" "F.Mask" "F.Paste")
			(net "SAS_EXP_GF_TX_DN15")
		)
		(pad "B80" smd rect
			(at 69.50075 -2.3495 180)
			(size 0.7112 4.191)
			(drill
				(offset 0 0.254)
			)
			(layers "F.Cu" "F.Mask" "F.Paste")
			(net "GND")
		)
		(pad "B81" smd rect
			(at 70.50024 -2.5908 180)
			(size 0.7112 3.2004)
			(layers "F.Cu" "F.Mask" "F.Paste")
			(net "GND")
		)
		(pad "B82" smd rect
			(at 71.49973 -2.3495 180)
			(size 0.7112 4.191)
			(drill
				(offset 0 0.254)
			)
			(layers "F.Cu" "F.Mask" "F.Paste")
			(net "GND")
		)
	)
)
